# BASEBOARD_FAB2 (Tioga Pass) — schematic netlist excerpt (pin names and nets, part order shuffled) for the footprints in the layout excerpt that follows; sources: Cadence DE-HDL packaged netlist, KiCad conversion of Wiwynn_Tioga_Pass_MB.brd

C5L3  CAP  100UF 4V 20% X5R  pkg 0805  page 220 : A = PVDDQ_DEF ; B = GND

U1M3  TPS2061  IC  pkg SM  page 176
  \out\  = P5V_USB
  GND  = GND
  OC_N  = FM_OC0_USB_N
  EN_N  = FM_USB_P0_EN_R_N
  \in\  = P5V_TPS2061

C6L5  CAP  10UF 4V 20% X6S  pkg 0603LF  page 230 : A = PVDDQ_KLM ; B = GND
C5G70  CAP_A  22.0UF 4V 20% X6S  pkg 0603V  page 242 : A = PVDDQ_DEF ; B = GND

(kicad_pcb
	(version 20260206)
	(generator "pcbnew")
	(generator_version "10.0")
	(general
		(thickness 1.6)
		(legacy_teardrops no)
	)
	(paper "A4")
	(title_block
		(title "Wiwynn_Tioga_Pass_MB.brd")
		(comment 1 "Tioga Pass / footprints 4282-4285 of 4770")
	)
	(layers
		(0 "F.Cu" signal "TOP")
		(4 "In1.Cu" signal "L2GND")
		(6 "In2.Cu" signal "L3")
		(8 "In3.Cu" signal "L4GND")
		(10 "In4.Cu" signal "L5")
		(12 "In5.Cu" signal "L6GND")
		(14 "In6.Cu" signal "L7VCC")
		(16 "In7.Cu" signal "L8VCC")
		(18 "In8.Cu" signal "L9GND")
		(20 "In9.Cu" signal "L10")
		(22 "In10.Cu" signal "L11GND")
		(24 "In11.Cu" signal "L12")
		(26 "In12.Cu" signal "L13GND")
		(2 "B.Cu" signal "BOTTOM")
		(9 "F.Adhes" user "F.Adhesive")
		(11 "B.Adhes" user "B.Adhesive")
		(13 "F.Paste" user "Package Geometry/Pastemask Top")
		(15 "B.Paste" user "Package Geometry/Pastemask Bottom")
		(5 "F.SilkS" user "Ref Des/Silkscreen Top")
		(7 "B.SilkS" user "Ref Des/Silkscreen Bottom")
		(1 "F.Mask" user "Board Geometry/Soldermask Top")
		(3 "B.Mask" user "Board Geometry/Soldermask Bottom")
		(17 "Dwgs.User" user "User.Drawings")
		(19 "Cmts.User" user "User.Comments")
		(21 "Eco1.User" user "User.Eco1")
		(23 "Eco2.User" user "User.Eco2")
		(25 "Edge.Cuts" user "Board Geometry/Outline")
		(27 "Margin" user)
		(31 "F.CrtYd" user "Package Geometry/Place Bound Top")
		(29 "B.CrtYd" user "Package Geometry/Place Bound Bottom")
		(35 "F.Fab" user "Ref Des/Assembly Top")
		(33 "B.Fab" user "Ref Des/Assembly Bottom")
	)
	(footprint ""
		(layer "B.Cu")
		(at 168.927526 -146.713448 90)
		(property "Reference" "C6L5"
			(at 0 0 90)
			(layer "B.SilkS")
			(hide yes)
			(effects
				(font
					(size 1.27 1.27)
				)
				(justify mirror)
			)
		)
		(property "Value" ""
			(at 0 0 90)
			(layer "B.Fab")
			(effects
				(font
					(size 1.27 1.27)
				)
				(justify mirror)
			)
		)
		(duplicate_pad_numbers_are_jumpers no)
		(fp_rect
			(start 0.4953 1.6002)
			(end -0.4953 -0.2032)
			(stroke
				(width 0)
				(type default)
			)
			(fill no)
			(layer "B.CrtYd")
		)
		(fp_line
			(start 0.4953 -0.2032)
			(end -0.4953 -0.2032)
			(stroke
				(width 0.1)
				(type default)
			)
			(layer "B.Fab")
		)
		(fp_line
			(start -0.4953 -0.2032)
			(end -0.4953 1.6002)
			(stroke
				(width 0.1)
				(type default)
			)
			(layer "B.Fab")
		)
		(fp_line
			(start 0.4953 1.6002)
			(end 0.4953 -0.2032)
			(stroke
				(width 0.1)
				(type default)
			)
			(layer "B.Fab")
		)
		(fp_line
			(start -0.4953 1.6002)
			(end 0.4953 1.6002)
			(stroke
				(width 0.1)
				(type default)
			)
			(layer "B.Fab")
		)
		(pad "1" smd rect
			(at 0 0 270)
			(size 0.762 0.889)
			(layers "B.Cu" "B.Mask" "B.Paste")
			(net "PVDDQ_KLM")
		)
		(pad "2" smd rect
			(at 0 1.397 270)
			(size 0.762 0.889)
			(layers "B.Cu" "B.Mask" "B.Paste")
			(net "GND")
		)
		(zone
			(layer "B.Cu")
			(hatch none 0.5)
			(connect_pads
				(clearance 0)
			)
			(min_thickness 0.25)
			(keepout
				(tracks not_allowed)
				(vias allowed)
				(pads allowed)
				(copperpour not_allowed)
				(footprints allowed)
			)
			(placement
				(enabled no)
				(sheetname "")
			)
			(fill
				(thermal_gap 0.5)
				(thermal_bridge_width 0.5)
				(island_removal_mode 0)
			)
			(polygon
				(pts
					(xy 169.880026 -147.094448) (xy 169.372026 -147.094448) (xy 169.372026 -146.332448) (xy 169.880026 -146.332448)
				)
			)
		)
	)
	(footprint ""
		(layer "B.Cu")
		(at 269.559532 -149.8092 90)
		(property "Reference" "C5G70"
			(at -1.14681 0.76708 180)
			(unlocked yes)
			(layer "B.SilkS")
			(effects
				(font
					(size 0.7874 0.5842)
					(thickness 0.1524)
				)
				(justify mirror)
			)
		)
		(property "Value" ""
			(at 0 0 90)
			(layer "B.Fab")
			(effects
				(font
					(size 1.27 1.27)
				)
				(justify mirror)
			)
		)
		(duplicate_pad_numbers_are_jumpers no)
		(fp_rect
			(start -0.4953 -0.2032)
			(end 0.4953 1.6002)
			(stroke
				(width 0)
				(type default)
			)
			(fill no)
			(layer "B.CrtYd")
		)
		(fp_line
			(start 0.4953 -0.2032)
			(end -0.4953 -0.2032)
			(stroke
				(width 0.1)
				(type default)
			)
			(layer "B.Fab")
		)
		(fp_line
			(start -0.4953 -0.2032)
			(end -0.4953 1.6002)
			(stroke
				(width 0.1)
				(type default)
			)
			(layer "B.Fab")
		)
		(fp_line
			(start 0.4953 1.6002)
			(end 0.4953 -0.2032)
			(stroke
				(width 0.1)
				(type default)
			)
			(layer "B.Fab")
		)
		(fp_line
			(start -0.4953 1.6002)
			(end 0.4953 1.6002)
			(stroke
				(width 0.1)
				(type default)
			)
			(layer "B.Fab")
		)
		(pad "1" smd rect
			(at 0 0 270)
			(size 0.762 0.889)
			(layers "B.Cu" "B.Mask" "B.Paste")
			(net "PVDDQ_DEF")
		)
		(pad "2" smd rect
			(at 0 1.397 270)
			(size 0.762 0.889)
			(layers "B.Cu" "B.Mask" "B.Paste")
			(net "GND")
		)
		(zone
			(layer "B.Cu")
			(hatch none 0.5)
			(connect_pads
				(clearance 0)
			)
			(min_thickness 0.25)
			(keepout
				(tracks not_allowed)
				(vias allowed)
				(pads allowed)
				(copperpour not_allowed)
				(footprints allowed)
			)
			(placement
				(enabled no)
				(sheetname "")
			)
			(fill
				(thermal_gap 0.5)
				(thermal_bridge_width 0.5)
				(island_removal_mode 0)
			)
			(polygon
				(pts
					(xy 270.004032 -149.4282) (xy 270.512032 -149.4282) (xy 270.512032 -150.1902) (xy 270.004032 -150.1902)
				)
			)
		)
	)
	(footprint ""
		(layer "B.Cu")
		(at 269.502128 -156.960824 90)
		(property "Reference" "C5L3"
			(at 0 0 90)
			(layer "B.SilkS")
			(hide yes)
			(effects
				(font
					(size 1.27 1.27)
				)
				(justify mirror)
			)
		)
		(property "Value" ""
			(at 0 0 90)
			(layer "B.Fab")
			(effects
				(font
					(size 1.27 1.27)
				)
				(justify mirror)
			)
		)
		(duplicate_pad_numbers_are_jumpers no)
		(fp_rect
			(start 0.7239 1.9939)
			(end -0.7239 -0.2159)
			(stroke
				(width 0)
				(type default)
			)
			(fill no)
			(layer "B.CrtYd")
		)
		(fp_line
			(start 0.7239 -0.2159)
			(end 0.7239 1.9939)
			(stroke
				(width 0.1)
				(type default)
			)
			(layer "B.Fab")
		)
		(fp_line
			(start -0.7239 -0.2159)
			(end 0.7239 -0.2159)
			(stroke
				(width 0.1)
				(type default)
			)
			(layer "B.Fab")
		)
		(fp_line
			(start 0.7239 1.9939)
			(end -0.7239 1.9939)
			(stroke
				(width 0.1)
				(type default)
			)
			(layer "B.Fab")
		)
		(fp_line
			(start -0.7239 1.9939)
			(end -0.7239 -0.2159)
			(stroke
				(width 0.1)
				(type default)
			)
			(layer "B.Fab")
		)
		(pad "1" smd rect
			(at 0 0 270)
			(size 1.27 1.016)
			(layers "B.Cu" "B.Mask" "B.Paste")
			(net "PVDDQ_DEF")
		)
		(pad "2" smd rect
			(at 0 1.778 270)
			(size 1.27 1.016)
			(layers "B.Cu" "B.Mask" "B.Paste")
			(net "GND")
		)
		(zone
			(layer "B.Cu")
			(hatch none 0.5)
			(connect_pads
				(clearance 0)
			)
			(min_thickness 0.25)
			(keepout
				(tracks not_allowed)
				(vias allowed)
				(pads allowed)
				(copperpour not_allowed)
				(footprints allowed)
			)
			(placement
				(enabled no)
				(sheetname "")
			)
			(fill
				(thermal_gap 0.5)
				(thermal_bridge_width 0.5)
				(island_removal_mode 0)
			)
			(polygon
				(pts
					(xy 270.772128 -157.595824) (xy 270.010128 -157.595824) (xy 270.010128 -156.325824) (xy 270.772128 -156.325824)
				)
			)
		)
	)
	(footprint ""
		(layer "B.Cu")
		(at 465.0232 -130.5052 90)
		(property "Reference" "U1M3"
			(at -5.83819 0.86614 0)
			(unlocked yes)
			(layer "B.SilkS")
			(effects
				(font
					(size 0.7874 0.5842)
					(thickness 0.1524)
				)
				(justify mirror)
			)
		)
		(property "Value" ""
			(at 0 0 90)
			(layer "B.Fab")
			(effects
				(font
					(size 1.27 1.27)
				)
				(justify mirror)
			)
		)
		(duplicate_pad_numbers_are_jumpers no)
		(fp_circle
			(center 1.395222 -0.155448)
			(end 1.395222 -0.028448)
			(stroke
				(width 0.254)
				(type default)
			)
			(fill no)
			(layer "B.SilkS")
		)
		(fp_rect
			(start -0.45847 2.400046)
			(end -2.20853 -0.500126)
			(stroke
				(width 0)
				(type default)
			)
			(fill no)
			(layer "B.CrtYd")
		)
		(fp_line
			(start -0.45847 -0.500126)
			(end -2.20853 -0.500126)
			(stroke
				(width 0.1)
				(type default)
			)
			(layer "B.Fab")
		)
		(fp_line
			(start -2.20853 -0.500126)
			(end -2.20853 2.400046)
			(stroke
				(width 0.1)
				(type default)
			)
			(layer "B.Fab")
		)
		(fp_line
			(start -0.45847 2.400046)
			(end -0.45847 -0.500126)
			(stroke
				(width 0.1)
				(type default)
			)
			(layer "B.Fab")
		)
		(fp_line
			(start -2.20853 2.400046)
			(end -0.45847 2.400046)
			(stroke
				(width 0.1)
				(type default)
			)
			(layer "B.Fab")
		)
		(fp_circle
			(center 1.395222 -0.155448)
			(end 1.395222 -0.028448)
			(stroke
				(width 0.254)
				(type default)
			)
			(fill no)
			(layer "B.Fab")
		)
		(pad "1" smd rect
			(at 0 0 270)
			(size 1.397 0.508)
			(layers "B.Cu" "B.Mask" "B.Paste")
			(net "P5V_USB")
		)
		(pad "2" smd rect
			(at 0 0.94996 270)
			(size 1.397 0.508)
			(layers "B.Cu" "B.Mask" "B.Paste")
			(net "GND")
		)
		(pad "3" smd rect
			(at 0 1.89992 270)
			(size 1.397 0.508)
			(layers "B.Cu" "B.Mask" "B.Paste")
			(net "FM_OC0_USB_N")
		)
		(pad "4" smd rect
			(at -2.667 1.89992 270)
			(size 1.397 0.508)
			(layers "B.Cu" "B.Mask" "B.Paste")
			(net "FM_USB_P0_EN_R_N")
		)
		(pad "5" smd rect
			(at -2.667 0 270)
			(size 1.397 0.508)
			(layers "B.Cu" "B.Mask" "B.Paste")
			(net "P5V_TPS2061")
		)
	)
)
